# S9S_MB_2U (Grand Teton) — schematic netlist excerpt (pin names and nets, part order shuffled) for the footprints in the layout excerpt that follows; sources: Cadence DE-HDL packaged netlist, KiCad conversion of 03242023_DA0F0TMBIJ0_F0T_Motherboard_J_brd_V01_OCP.brd

C299  Q_CAP  22UF 4V 20% X6S  pkg C0402  page 77 : A = PVCCIN_CPU1 ; B = GND
D89  Q_LED  IC  pkg SMLF  page 255 : A = LED_PWRGD_CPUPWRGD_GTL ; C = LED_PWRGD_CPUPWRGD_GTL_D

(kicad_pcb
	(version 20260206)
	(generator "pcbnew")
	(generator_version "10.0")
	(general
		(thickness 1.6)
		(legacy_teardrops no)
	)
	(paper "A4")
	(title_block
		(title "03242023_DA0F0TMBIJ0_F0T_Motherboard_J_brd_V01_OCP.brd")
		(comment 1 "Grand Teton / footprints 124-125 of 6105")
	)
	(layers
		(0 "F.Cu" signal "TOP")
		(4 "In1.Cu" signal "GND")
		(6 "In2.Cu" signal "IN1")
		(8 "In3.Cu" signal "GND1")
		(10 "In4.Cu" signal "IN2")
		(12 "In5.Cu" signal "GND2")
		(14 "In6.Cu" signal "IN3")
		(16 "In7.Cu" signal "GND3")
		(18 "In8.Cu" signal "VCC")
		(20 "In9.Cu" signal "VCC1")
		(22 "In10.Cu" signal "GND4")
		(24 "In11.Cu" signal "IN4")
		(26 "In12.Cu" signal "GND5")
		(28 "In13.Cu" signal "IN5")
		(30 "In14.Cu" signal "GND6")
		(32 "In15.Cu" signal "IN6")
		(34 "In16.Cu" signal "GND7")
		(2 "B.Cu" signal "BOTTOM")
		(9 "F.Adhes" user "F.Adhesive")
		(11 "B.Adhes" user "B.Adhesive")
		(13 "F.Paste" user "Package Geometry/Pastemask Top")
		(15 "B.Paste" user "Package Geometry/Pastemask Bottom")
		(5 "F.SilkS" user "Ref Des/Silkscreen Top")
		(7 "B.SilkS" user "Ref Des/Silkscreen Bottom")
		(1 "F.Mask" user "Board Geometry/Soldermask Top")
		(3 "B.Mask" user "Board Geometry/Soldermask Bottom")
		(17 "Dwgs.User" user "User.Drawings")
		(19 "Cmts.User" user "User.Comments")
		(21 "Eco1.User" user "User.Eco1")
		(23 "Eco2.User" user "User.Eco2")
		(25 "Edge.Cuts" user "Board Geometry/Outline")
		(27 "Margin" user)
		(31 "F.CrtYd" user "Package Geometry/Place Bound Top")
		(29 "B.CrtYd" user "Package Geometry/Place Bound Bottom")
		(35 "F.Fab" user "Ref Des/Assembly Top")
		(33 "B.Fab" user "Ref Des/Assembly Bottom")
	)
	(footprint ""
		(layer "F.Cu")
		(at 87.382096 -70.78599)
		(property "Reference" "D89"
			(at -44.586906 50.178462 90)
			(unlocked yes)
			(layer "F.SilkS")
			(effects
				(font
					(size 0.635 0.4064)
					(thickness 0.1524)
				)
				(justify left)
			)
		)
		(property "Value" ""
			(at 0 0 0)
			(layer "F.Fab")
			(effects
				(font
					(size 1.27 1.27)
				)
			)
		)
		(duplicate_pad_numbers_are_jumpers no)
		(fp_line
			(start -0.90678 0.4826)
			(end -0.90678 -0.4699)
			(stroke
				(width 0.1524)
				(type default)
			)
			(layer "F.SilkS")
		)
		(fp_line
			(start -0.89408 -0.4826)
			(end 0.90678 -0.4826)
			(stroke
				(width 0.1524)
				(type default)
			)
			(layer "F.SilkS")
		)
		(fp_line
			(start -0.79248 -0.4826)
			(end 1.03378 -0.4826)
			(stroke
				(width 0.1524)
				(type default)
			)
			(layer "F.SilkS")
		)
		(fp_line
			(start -0.64008 -0.4826)
			(end 1.16078 -0.4826)
			(stroke
				(width 0.1524)
				(type default)
			)
			(layer "F.SilkS")
		)
		(fp_line
			(start 0.90678 -0.4826)
			(end 0.90678 0.4826)
			(stroke
				(width 0.1524)
				(type default)
			)
			(layer "F.SilkS")
		)
		(fp_line
			(start 0.90678 0.4826)
			(end -0.90678 0.4826)
			(stroke
				(width 0.1524)
				(type default)
			)
			(layer "F.SilkS")
		)
		(fp_line
			(start 1.03378 -0.4826)
			(end 1.03378 0.4826)
			(stroke
				(width 0.1524)
				(type default)
			)
			(layer "F.SilkS")
		)
		(fp_line
			(start 1.03378 0.4826)
			(end -0.79248 0.4826)
			(stroke
				(width 0.1524)
				(type default)
			)
			(layer "F.SilkS")
		)
		(fp_line
			(start 1.16078 -0.4826)
			(end 1.16078 0.4826)
			(stroke
				(width 0.1524)
				(type default)
			)
			(layer "F.SilkS")
		)
		(fp_line
			(start 1.16078 0.4826)
			(end -0.64008 0.4826)
			(stroke
				(width 0.1524)
				(type default)
			)
			(layer "F.SilkS")
		)
		(fp_line
			(start -0.499872 -0.249936)
			(end 0.499872 -0.249936)
			(stroke
				(width 0.1)
				(type default)
			)
			(layer "F.Fab")
		)
		(fp_line
			(start -0.499872 0.249936)
			(end -0.499872 -0.249936)
			(stroke
				(width 0.1)
				(type default)
			)
			(layer "F.Fab")
		)
		(fp_line
			(start 0.499872 -0.249936)
			(end 0.499872 0.249936)
			(stroke
				(width 0.1)
				(type default)
			)
			(layer "F.Fab")
		)
		(fp_line
			(start 0.499872 0.249936)
			(end -0.499872 0.249936)
			(stroke
				(width 0.1)
				(type default)
			)
			(layer "F.Fab")
		)
		(pad "A" smd rect
			(at -0.47498 0)
			(size 0.6096 0.7112)
			(layers "F.Cu" "F.Mask" "F.Paste")
			(net "LED_PWRGD_CPUPWRGD_GTL")
		)
		(pad "C" smd rect
			(at 0.47498 0)
			(size 0.6096 0.7112)
			(layers "F.Cu" "F.Mask" "F.Paste")
			(net "LED_PWRGD_CPUPWRGD_GTL_D")
		)
	)
	(footprint ""
		(layer "F.Cu")
		(at 107.2769 -256.6543 -90)
		(property "Reference" "C299"
			(at 0 0 270)
			(layer "F.SilkS")
			(hide yes)
			(effects
				(font
					(size 1.27 1.27)
				)
			)
		)
		(property "Value" ""
			(at 0 0 270)
			(layer "F.Fab")
			(effects
				(font
					(size 1.27 1.27)
				)
			)
		)
		(duplicate_pad_numbers_are_jumpers no)
		(fp_line
			(start -0.7874 0.4064)
			(end -0.7874 -0.4064)
			(stroke
				(width 0.1524)
				(type default)
			)
			(layer "F.SilkS")
		)
		(fp_line
			(start 0.7874 0.4064)
			(end -0.7874 0.4064)
			(stroke
				(width 0.1524)
				(type default)
			)
			(layer "F.SilkS")
		)
		(fp_line
			(start -0.7874 -0.4064)
			(end 0.7874 -0.4064)
			(stroke
				(width 0.1524)
				(type default)
			)
			(layer "F.SilkS")
		)
		(fp_line
			(start 0.7874 -0.4064)
			(end 0.7874 0.4064)
			(stroke
				(width 0.1524)
				(type default)
			)
			(layer "F.SilkS")
		)
		(fp_line
			(start -0.67945 0.3048)
			(end -0.67945 -0.305054)
			(stroke
				(width 0.1)
				(type default)
			)
			(layer "F.Fab")
		)
		(fp_line
			(start -0.12065 0.3048)
			(end -0.67945 0.3048)
			(stroke
				(width 0.1)
				(type default)
			)
			(layer "F.Fab")
		)
		(fp_line
			(start 0.120396 0.3048)
			(end 0.120396 0.2794)
			(stroke
				(width 0.1)
				(type default)
			)
			(layer "F.Fab")
		)
		(fp_line
			(start 0.67945 0.3048)
			(end 0.120396 0.3048)
			(stroke
				(width 0.1)
				(type default)
			)
			(layer "F.Fab")
		)
		(fp_line
			(start -0.12065 0.2794)
			(end -0.12065 0.3048)
			(stroke
				(width 0.1)
				(type default)
			)
			(layer "F.Fab")
		)
		(fp_line
			(start 0.120396 0.2794)
			(end -0.12065 0.2794)
			(stroke
				(width 0.1)
				(type default)
			)
			(layer "F.Fab")
		)
		(fp_line
			(start -0.12065 -0.2794)
			(end 0.12065 -0.2794)
			(stroke
				(width 0.1)
				(type default)
			)
			(layer "F.Fab")
		)
		(fp_line
			(start 0.12065 -0.2794)
			(end 0.12065 -0.3048)
			(stroke
				(width 0.1)
				(type default)
			)
			(layer "F.Fab")
		)
		(fp_line
			(start 0.12065 -0.3048)
			(end 0.67945 -0.3048)
			(stroke
				(width 0.1)
				(type default)
			)
			(layer "F.Fab")
		)
		(fp_line
			(start 0.67945 -0.3048)
			(end 0.67945 0.3048)
			(stroke
				(width 0.1)
				(type default)
			)
			(layer "F.Fab")
		)
		(fp_line
			(start -0.67945 -0.305054)
			(end -0.12065 -0.305054)
			(stroke
				(width 0.1)
				(type default)
			)
			(layer "F.Fab")
		)
		(fp_line
			(start -0.12065 -0.305054)
			(end -0.12065 -0.2794)
			(stroke
				(width 0.1)
				(type default)
			)
			(layer "F.Fab")
		)
		(pad "1" smd circle
			(at -0.40005 0 270)
			(size 0 0)
			(layers "F.Cu" "F.Mask" "F.Paste")
			(net "PVCCIN_CPU1")
		)
		(pad "2" smd circle
			(at 0.40005 0 270)
			(size 0 0)
			(layers "F.Cu" "F.Mask" "F.Paste")
			(net "GND")
		)
	)
)
